#ISCELL
  mstr_misc prelim *
  *
#ISCELL
  mstr_symbols design_note *
  *
#ISCELL
  mstr_symbols intel_corp_bpage *
  *
#ISCELL
  mstr_standard offpage *
  page67_i1
#ISCELL
  mstr_standard tap *
  page67_i100
#ISCELL
  mstr_standard tap *
  page67_i101
#ISCELL
  mstr_standard tap *
  page67_i102
#ISCELL
  mstr_standard tap *
  page67_i103
#ISCELL
  mstr_standard tap *
  page67_i104
#ISCELL
  mstr_standard tap *
  page67_i105
#ISCELL
  mstr_standard tap *
  page67_i106
#ISCELL
  mstr_standard tap *
  page67_i107
#ISCELL
  mstr_standard tap *
  page67_i108
#ISCELL
  mstr_standard tap *
  page67_i109
#ISCELL
  mstr_standard tap *
  page67_i110
#ISCELL
  mstr_standard tap *
  page67_i111
#ISCELL
  mstr_standard tap *
  page67_i112
#ISCELL
  mstr_standard tap *
  page67_i113
#ISCELL
  mstr_standard tap *
  page67_i114
#ISCELL
  mstr_standard tap *
  page67_i115
#ISCELL
  mstr_standard tap *
  page67_i116
#ISCELL
  mstr_standard tap *
  page67_i117
#ISCELL
  mstr_standard tap *
  page67_i118
#ISCELL
  mstr_standard tap *
  page67_i119
#ISCELL
  mstr_standard tap *
  page67_i120
#ISCELL
  mstr_standard tap *
  page67_i121
#ISCELL
  mstr_standard tap *
  page67_i122
#ISCELL
  mstr_standard tap *
  page67_i123
#ISCELL
  mstr_standard tap *
  page67_i124
#ISCELL
  mstr_standard tap *
  page67_i125
#ISCELL
  mstr_standard tap *
  page67_i126
#ISCELL
  mstr_standard tap *
  page67_i127
#ISCELL
  mstr_standard tap *
  page67_i128
#ISCELL
  mstr_standard tap *
  page67_i129
#ISCELL
  mstr_standard tap *
  page67_i130
#ISCELL
  mstr_standard tap *
  page67_i131
#CELL
  chpset_lib skx_ext_b *
  page67_i132
#ISCELL
  mstr_standard tap *
  page67_i14
#ISCELL
  mstr_standard tap *
  page67_i16
#ISCELL
  mstr_standard offpage *
  page67_i2
#ISCELL
  mstr_standard tap *
  page67_i20
#ISCELL
  mstr_standard tap *
  page67_i21
#ISCELL
  mstr_standard tap *
  page67_i26
#ISCELL
  mstr_standard tap *
  page67_i27
#ISCELL
  mstr_standard tap *
  page67_i28
#ISCELL
  mstr_standard tap *
  page67_i34
#ISCELL
  mstr_standard tap *
  page67_i36
#ISCELL
  mstr_standard tap *
  page67_i40
#ISCELL
  mstr_standard tap *
  page67_i41
#ISCELL
  mstr_standard tap *
  page67_i42
#ISCELL
  mstr_standard tap *
  page67_i43
#ISCELL
  mstr_standard tap *
  page67_i46
#ISCELL
  mstr_standard tap *
  page67_i48
#ISCELL
  mstr_standard tap *
  page67_i49
#ISCELL
  mstr_standard tap *
  page67_i5
#ISCELL
  mstr_standard tap *
  page67_i51
#ISCELL
  mstr_standard tap *
  page67_i53
#ISCELL
  mstr_standard tap *
  page67_i54
#ISCELL
  mstr_standard tap *
  page67_i58
#ISCELL
  mstr_standard tap *
  page67_i6
#ISCELL
  mstr_standard tap *
  page67_i61
#ISCELL
  mstr_standard tap *
  page67_i62
#ISCELL
  mstr_standard tap *
  page67_i66
#ISCELL
  mstr_standard tap *
  page67_i67
#ISCELL
  mstr_standard tap *
  page67_i69
#ISCELL
  mstr_standard tap *
  page67_i7
#ISCELL
  mstr_standard tap *
  page67_i72
#ISCELL
  mstr_standard tap *
  page67_i73
#ISCELL
  mstr_standard tap *
  page67_i74
#ISCELL
  mstr_standard tap *
  page67_i78
#ISCELL
  mstr_standard tap *
  page67_i81
#ISCELL
  mstr_standard tap *
  page67_i83
#ISCELL
  mstr_standard offpage *
  page67_i84
#ISCELL
  mstr_standard offpage *
  page67_i85
#ISCELL
  mstr_standard tap *
  page67_i86
#ISCELL
  mstr_standard tap *
  page67_i87
#ISCELL
  mstr_standard tap *
  page67_i88
#ISCELL
  mstr_standard tap *
  page67_i89
#ISCELL
  mstr_standard tap *
  page67_i90
#ISCELL
  mstr_standard tap *
  page67_i91
#ISCELL
  mstr_standard tap *
  page67_i92
#ISCELL
  mstr_standard tap *
  page67_i93
#ISCELL
  mstr_standard tap *
  page67_i94
#ISCELL
  mstr_standard tap *
  page67_i95
#ISCELL
  mstr_standard tap *
  page67_i96
#ISCELL
  mstr_standard tap *
  page67_i97
#ISCELL
  mstr_standard tap *
  page67_i98
#ISCELL
  mstr_standard tap *
  page67_i99
